(kicad_pcb
	(version 20260206)
	(generator "pcbnew")
	(generator_version "10.0")
	(general
		(thickness 1.6)
		(legacy_teardrops no)
	)
	(paper "A4")
	(title_block
		(title "Bryce Canyon_R.DPB_16317-1_OCP.brd")
		(comment 1 "Bryce Canyon / footprints 514-517 of 2099")
	)
	(layers
		(0 "F.Cu" signal "TOP")
		(4 "In1.Cu" signal "L2GND")
		(6 "In2.Cu" signal "L3")
		(8 "In3.Cu" signal "L4VCC")
		(10 "In4.Cu" signal "L5VCC")
		(12 "In5.Cu" signal "L6")
		(14 "In6.Cu" signal "L7GND")
		(2 "B.Cu" signal "BOTTOM")
		(9 "F.Adhes" user "F.Adhesive")
		(11 "B.Adhes" user "B.Adhesive")
		(13 "F.Paste" user "Package Geometry/Pastemask Top")
		(15 "B.Paste" user "Package Geometry/Pastemask Bottom")
		(5 "F.SilkS" user "Ref Des/Silkscreen Top")
		(7 "B.SilkS" user "Ref Des/Silkscreen Bottom")
		(1 "F.Mask" user "Board Geometry/Soldermask Top")
		(3 "B.Mask" user "Board Geometry/Soldermask Bottom")
		(17 "Dwgs.User" user "User.Drawings")
		(19 "Cmts.User" user "User.Comments")
		(21 "Eco1.User" user "User.Eco1")
		(23 "Eco2.User" user "User.Eco2")
		(25 "Edge.Cuts" user "Board Geometry/Outline")
		(27 "Margin" user)
		(31 "F.CrtYd" user "Package Geometry/Place Bound Top")
		(29 "B.CrtYd" user "Package Geometry/Place Bound Bottom")
		(35 "F.Fab" user "Ref Des/Assembly Top")
		(33 "B.Fab" user "Ref Des/Assembly Bottom")
	)
	(footprint ""
		(layer "F.Cu")
		(at 43.528996 -362.077 180)
		(property "Reference" "Q211"
			(at 0 0 180)
			(layer "F.SilkS")
			(hide yes)
			(effects
				(font
					(size 1.27 1.27)
				)
			)
		)
		(property "Value" "2N7002K-2-GP"
			(at 0.127 -8.9662 180)
			(unlocked yes)
			(layer "F.Fab")
			(hide yes)
			(effects
				(font
					(size 1.016 1.016)
					(thickness 0.1524)
				)
			)
		)
		(property "Device Type" "SOT23DGS2D4H44"
			(at 0.127 -10.4902 180)
			(unlocked yes)
			(layer "F.Fab")
			(hide yes)
			(effects
				(font
					(size 1.016 1.016)
					(thickness 0.1524)
				)
			)
		)
		(duplicate_pad_numbers_are_jumpers no)
		(fp_line
			(start 1.651 1.778)
			(end 1.651 -1.778)
			(stroke
				(width 0.1524)
				(type default)
			)
			(layer "F.SilkS")
		)
		(fp_line
			(start 1.651 -1.778)
			(end -1.651 -1.778)
			(stroke
				(width 0.1524)
				(type default)
			)
			(layer "F.SilkS")
		)
		(fp_line
			(start -1.651 1.778)
			(end 1.651 1.778)
			(stroke
				(width 0.1524)
				(type default)
			)
			(layer "F.SilkS")
		)
		(fp_line
			(start -1.651 -1.778)
			(end -1.651 1.778)
			(stroke
				(width 0.1524)
				(type default)
			)
			(layer "F.SilkS")
		)
		(fp_poly
			(pts
				(xy -1.778 1.8796) (xy -1.778 -1.8796) (xy 1.778 -1.8796) (xy 1.778 1.8796)
			)
			(stroke
				(width 0)
				(type default)
			)
			(fill no)
			(layer "F.CrtYd")
		)
		(fp_poly
			(pts
				(xy -1.778 1.8796) (xy -1.778 -1.8796) (xy 1.778 -1.8796) (xy 1.778 1.8796)
			)
			(stroke
				(width 0)
				(type default)
			)
			(fill no)
			(layer "F.Fab")
		)
		(pad "D" smd custom
			(at 0 -0.9525 180)
			(size 0.1905 0.1905)
			(layers "F.Cu" "F.Mask" "F.Paste")
			(net "GATE_FAN0")
			(options
				(clearance outline)
				(anchor circle)
			)
			(primitives
				(gr_poly
					(pts
						(arc
							(start -0.1778 0.5715)
							(mid -0.321484 0.511984)
							(end -0.381 0.3683)
						)
						(arc
							(start -0.381 -0.3683)
							(mid -0.321484 -0.511984)
							(end -0.1778 -0.5715)
						)
						(arc
							(start 0.1778 -0.5715)
							(mid 0.321484 -0.511984)
							(end 0.381 -0.3683)
						)
						(arc
							(start 0.381 0.3683)
							(mid 0.321484 0.511984)
							(end 0.1778 0.5715)
						)
					)
					(width 0)
					(fill yes)
				)
			)
		)
		(pad "G" smd custom
			(at -0.98425 0.9525 180)
			(size 0.1905 0.1905)
			(layers "F.Cu" "F.Mask" "F.Paste")
			(net "FAN_EN")
			(options
				(clearance outline)
				(anchor circle)
			)
			(primitives
				(gr_poly
					(pts
						(arc
							(start -0.1778 0.5715)
							(mid -0.321484 0.511984)
							(end -0.381 0.3683)
						)
						(arc
							(start -0.381 -0.3683)
							(mid -0.321484 -0.511984)
							(end -0.1778 -0.5715)
						)
						(arc
							(start 0.1778 -0.5715)
							(mid 0.321484 -0.511984)
							(end 0.381 -0.3683)
						)
						(arc
							(start 0.381 0.3683)
							(mid 0.321484 0.511984)
							(end 0.1778 0.5715)
						)
					)
					(width 0)
					(fill yes)
				)
			)
		)
		(pad "S" smd custom
			(at 0.98425 0.9525 180)
			(size 0.1905 0.1905)
			(layers "F.Cu" "F.Mask" "F.Paste")
			(net "GND")
			(options
				(clearance outline)
				(anchor circle)
			)
			(primitives
				(gr_poly
					(pts
						(arc
							(start -0.1778 0.5715)
							(mid -0.321484 0.511984)
							(end -0.381 0.3683)
						)
						(arc
							(start -0.381 -0.3683)
							(mid -0.321484 -0.511984)
							(end -0.1778 -0.5715)
						)
						(arc
							(start 0.1778 -0.5715)
							(mid 0.321484 -0.511984)
							(end 0.381 -0.3683)
						)
						(arc
							(start 0.381 0.3683)
							(mid 0.321484 0.511984)
							(end 0.1778 0.5715)
						)
					)
					(width 0)
					(fill yes)
				)
			)
		)
	)
	(footprint ""
		(layer "F.Cu")
		(at 365.125 -155.6004 -90)
		(property "Reference" "R508"
			(at 0 0 270)
			(layer "F.SilkS")
			(hide yes)
			(effects
				(font
					(size 1.27 1.27)
				)
			)
		)
		(property "Value" "2R6F-GP"
			(at -0.0508 -4.8514 270)
			(unlocked yes)
			(layer "F.Fab")
			(hide yes)
			(effects
				(font
					(size 1.016 1.016)
					(thickness 0.1524)
				)
			)
		)
		(property "Device Type" "R1206H26"
			(at 0 -6.3754 270)
			(unlocked yes)
			(layer "F.Fab")
			(hide yes)
			(effects
				(font
					(size 1.016 1.016)
					(thickness 0.1524)
				)
			)
		)
		(duplicate_pad_numbers_are_jumpers no)
		(fp_line
			(start -1.016 2.2352)
			(end -1.016 -2.2352)
			(stroke
				(width 0.1524)
				(type default)
			)
			(layer "F.SilkS")
		)
		(fp_line
			(start 1.016 2.2352)
			(end -1.016 2.2352)
			(stroke
				(width 0.1524)
				(type default)
			)
			(layer "F.SilkS")
		)
		(fp_line
			(start -1.016 -2.2352)
			(end 1.016 -2.2352)
			(stroke
				(width 0.1524)
				(type default)
			)
			(layer "F.SilkS")
		)
		(fp_line
			(start 1.016 -2.2352)
			(end 1.016 2.2352)
			(stroke
				(width 0.1524)
				(type default)
			)
			(layer "F.SilkS")
		)
		(fp_rect
			(start -1.0922 2.3114)
			(end 1.0922 -2.3114)
			(stroke
				(width 0)
				(type default)
			)
			(fill no)
			(layer "F.CrtYd")
		)
		(fp_poly
			(pts
				(xy -1.0922 -2.3114) (xy 1.0922 -2.3114) (xy 1.0922 2.3114) (xy -1.0922 2.3114)
			)
			(stroke
				(width 0)
				(type default)
			)
			(fill no)
			(layer "F.Fab")
		)
		(pad "1" smd rect
			(at 0 -1.397 270)
			(size 1.651 1.27)
			(layers "F.Cu" "F.Mask" "F.Paste")
			(net "P12V_HDD19")
		)
		(pad "2" smd rect
			(at 0 1.397 270)
			(size 1.651 1.27)
			(layers "F.Cu" "F.Mask" "F.Paste")
			(net "12V_PRE_19")
		)
	)
	(footprint ""
		(layer "F.Cu")
		(at 169.672 -361.696)
		(property "Reference" "C545"
			(at 0 0 0)
			(layer "F.SilkS")
			(hide yes)
			(effects
				(font
					(size 1.27 1.27)
				)
			)
		)
		(property "Value" "SCD1U25V2KX-2-GP"
			(at 1.1811 -2.7051 0)
			(unlocked yes)
			(layer "F.Fab")
			(hide yes)
			(effects
				(font
					(size 1.016 1.016)
					(thickness 0.1524)
				)
			)
		)
		(property "Device Type" "C402H22"
			(at 1.1811 -4.2291 0)
			(unlocked yes)
			(layer "F.Fab")
			(hide yes)
			(effects
				(font
					(size 1.016 1.016)
					(thickness 0.1524)
				)
			)
		)
		(duplicate_pad_numbers_are_jumpers no)
		(fp_rect
			(start -0.4318 0.9525)
			(end 0.4318 -0.9525)
			(stroke
				(width 0)
				(type default)
			)
			(fill no)
			(layer "F.CrtYd")
		)
		(fp_rect
			(start -0.4318 0.9525)
			(end 0.4318 -0.9525)
			(stroke
				(width 0)
				(type default)
			)
			(fill no)
			(layer "F.Fab")
		)
		(pad "1" smd custom
			(at 0 -0.4445)
			(size 0.1524 0.1524)
			(layers "F.Cu" "F.Mask" "F.Paste")
			(net "MB0_PSET_R")
			(options
				(clearance outline)
				(anchor circle)
			)
			(primitives
				(gr_poly
					(pts
						(arc
							(start 0.3048 -0.2032)
							(mid 0.275042 -0.275042)
							(end 0.2032 -0.3048)
						)
						(arc
							(start -0.2032 -0.3048)
							(mid -0.275042 -0.275042)
							(end -0.3048 -0.2032)
						)
						(arc
							(start -0.3048 0.2032)
							(mid -0.275042 0.275042)
							(end -0.2032 0.3048)
						)
						(arc
							(start 0.2032 0.3048)
							(mid 0.275042 0.275042)
							(end 0.3048 0.2032)
						)
					)
					(width 0)
					(fill yes)
				)
			)
		)
		(pad "2" smd custom
			(at 0 0.4445)
			(size 0.1524 0.1524)
			(layers "F.Cu" "F.Mask" "F.Paste")
			(net "AGND_CURRENT_MON")
			(options
				(clearance outline)
				(anchor circle)
			)
			(primitives
				(gr_poly
					(pts
						(arc
							(start 0.3048 -0.2032)
							(mid 0.275042 -0.275042)
							(end 0.2032 -0.3048)
						)
						(arc
							(start -0.2032 -0.3048)
							(mid -0.275042 -0.275042)
							(end -0.3048 -0.2032)
						)
						(arc
							(start -0.3048 0.2032)
							(mid -0.275042 0.275042)
							(end -0.2032 0.3048)
						)
						(arc
							(start 0.2032 0.3048)
							(mid 0.275042 0.275042)
							(end 0.3048 0.2032)
						)
					)
					(width 0)
					(fill yes)
				)
			)
		)
	)
	(footprint ""
		(layer "F.Cu")
		(at 137.538968 -97.404428 -90)
		(property "Reference" "R394"
			(at 0 0 270)
			(layer "F.SilkS")
			(hide yes)
			(effects
				(font
					(size 1.27 1.27)
				)
			)
		)
		(property "Value" "4K7R2F-GP"
			(at 0.064008 -3.993896 270)
			(unlocked yes)
			(layer "F.Fab")
			(hide yes)
			(effects
				(font
					(size 1.016 1.016)
					(thickness 0.1524)
				)
			)
		)
		(property "Device Type" "R402H16"
			(at 0.064008 -5.517896 270)
			(unlocked yes)
			(layer "F.Fab")
			(hide yes)
			(effects
				(font
					(size 1.016 1.016)
					(thickness 0.1524)
				)
			)
		)
		(duplicate_pad_numbers_are_jumpers no)
		(fp_line
			(start -0.508 -0.9398)
			(end -0.508 0.9398)
			(stroke
				(width 0.1524)
				(type default)
			)
			(layer "F.SilkS")
		)
		(fp_line
			(start 0.508 -0.9398)
			(end -0.508 -0.9398)
			(stroke
				(width 0.1524)
				(type default)
			)
			(layer "F.SilkS")
		)
		(fp_rect
			(start -0.508 0.9398)
			(end 0.508 -0.9398)
			(stroke
				(width 0)
				(type default)
			)
			(fill no)
			(layer "F.CrtYd")
		)
		(fp_rect
			(start -0.508 0.9398)
			(end 0.508 -0.9398)
			(stroke
				(width 0)
				(type default)
			)
			(fill no)
			(layer "F.Fab")
		)
		(pad "1" smd custom
			(at 0 -0.4445 270)
			(size 0.1397 0.1397)
			(layers "F.Cu" "F.Mask" "F.Paste")
			(net "DRIVE_B_16_ACT")
			(options
				(clearance outline)
				(anchor circle)
			)
			(primitives
				(gr_poly
					(pts
						(arc
							(start -0.1778 -0.2794)
							(mid -0.249642 -0.249642)
							(end -0.2794 -0.1778)
						)
						(arc
							(start -0.2794 0.1778)
							(mid -0.249642 0.249642)
							(end -0.1778 0.2794)
						)
						(arc
							(start 0.1778 0.2794)
							(mid 0.249642 0.249642)
							(end 0.2794 0.1778)
						)
						(arc
							(start 0.2794 -0.1778)
							(mid 0.249642 -0.249642)
							(end 0.1778 -0.2794)
						)
					)
					(width 0)
					(fill yes)
				)
			)
		)
		(pad "2" smd custom
			(at 0 0.4445 270)
			(size 0.1397 0.1397)
			(layers "F.Cu" "F.Mask" "F.Paste")
			(net "GND")
			(options
				(clearance outline)
				(anchor circle)
			)
			(primitives
				(gr_poly
					(pts
						(arc
							(start -0.1778 -0.2794)
							(mid -0.249642 -0.249642)
							(end -0.2794 -0.1778)
						)
						(arc
							(start -0.2794 0.1778)
							(mid -0.249642 0.249642)
							(end -0.1778 0.2794)
						)
						(arc
							(start 0.1778 0.2794)
							(mid 0.249642 0.249642)
							(end 0.2794 0.1778)
						)
						(arc
							(start 0.2794 -0.1778)
							(mid 0.249642 -0.249642)
							(end 0.1778 -0.2794)
						)
					)
					(width 0)
					(fill yes)
				)
			)
		)
	)
)
